(kicad_pcb
	(version 20241229)
	(generator "pcbnew")
	(generator_version "9.0")
	(general
		(thickness 1.711)
		(legacy_teardrops no)
	)
	(paper "A4")
	(title_block
		(title "Antmicro Baseboard for Jetson AGX Thor")
		(date "2026-02-18")
		(rev "1.1.0")
		(company "Antmicro Ltd")
		(comment 1 "www.antmicro.com")
		(comment 9 "footprints 614-618 of 1170")
	)
	(layers
		(0 "F.Cu" signal)
		(4 "In1.Cu" signal)
		(6 "In2.Cu" signal)
		(8 "In3.Cu" signal)
		(10 "In4.Cu" jumper)
		(12 "In5.Cu" signal)
		(14 "In6.Cu" signal)
		(16 "In7.Cu" signal)
		(18 "In8.Cu" signal)
		(2 "B.Cu" signal)
		(9 "F.Adhes" user "F.Adhesive")
		(11 "B.Adhes" user "B.Adhesive")
		(13 "F.Paste" user)
		(15 "B.Paste" user)
		(5 "F.SilkS" user "F.Silkscreen")
		(7 "B.SilkS" user "B.Silkscreen")
		(1 "F.Mask" user)
		(3 "B.Mask" user)
		(17 "Dwgs.User" user "User.Drawings")
		(19 "Cmts.User" user "User.Comments")
		(21 "Eco1.User" user "User.Eco1")
		(23 "Eco2.User" user "User.Eco2")
		(25 "Edge.Cuts" user)
		(27 "Margin" user)
		(31 "F.CrtYd" user "F.Courtyard")
		(29 "B.CrtYd" user "B.Courtyard")
		(35 "F.Fab" user)
		(33 "B.Fab" user)
	)
	(footprint "antmicro-footprints:R_0402_1005Metric"
		(layer "F.Cu")
		(at 180.889468 66.47 -90)
		(descr "Resistor SMD 0402")
		(tags "resistor SMD 0402")
		(property "Reference" "R30"
			(at -3.01 0.3 90)
			(layer "F.SilkS")
			(effects
				(font
					(size 0.7 0.7)
					(thickness 0.15)
				)
				(justify right top)
			)
		)
		(property "Value" "R_200k_0402"
			(at -1.011843 1.772047 90)
			(layer "F.Fab")
			(effects
				(font
					(size 0.7 0.7)
					(thickness 0.15)
				)
				(justify right top)
			)
		)
		(property "Datasheet" "https://www.bourns.com/docs/product-datasheets/cr.pdf"
			(at 0 0 90)
			(layer "F.Fab")
			(hide yes)
			(effects
				(font
					(size 1.27 1.27)
					(thickness 0.15)
				)
			)
		)
		(property "Description" "SMD Chip Resistor, 200 kohm, ± 1%, 62.5 mW, 0402 [1005 Metric], Thick Film, General Purpose"
			(at 0 0 90)
			(layer "F.Fab")
			(hide yes)
			(effects
				(font
					(size 1.27 1.27)
					(thickness 0.15)
				)
			)
		)
		(property "MPN" "CR0402-FX-2003GLF"
			(at 0 0 270)
			(unlocked yes)
			(layer "F.Fab")
			(hide yes)
			(effects
				(font
					(size 1 1)
					(thickness 0.15)
				)
			)
		)
		(property "Manufacturer" "Bourns"
			(at 0 0 270)
			(unlocked yes)
			(layer "F.Fab")
			(hide yes)
			(effects
				(font
					(size 1 1)
					(thickness 0.15)
				)
			)
		)
		(property "License" "Apache-2.0"
			(at 0 0 270)
			(unlocked yes)
			(layer "F.Fab")
			(hide yes)
			(effects
				(font
					(size 1 1)
					(thickness 0.15)
				)
			)
		)
		(property "Author" "Antmicro"
			(at 0 0 270)
			(unlocked yes)
			(layer "F.Fab")
			(hide yes)
			(effects
				(font
					(size 1 1)
					(thickness 0.15)
				)
			)
		)
		(property "Val" "200k"
			(at 0 0 270)
			(unlocked yes)
			(layer "F.Fab")
			(hide yes)
			(effects
				(font
					(size 1 1)
					(thickness 0.15)
				)
			)
		)
		(property "Tolerance" "1%"
			(at 0 0 270)
			(unlocked yes)
			(layer "F.Fab")
			(hide yes)
			(effects
				(font
					(size 1 1)
					(thickness 0.15)
				)
			)
		)
		(component_classes
			(class "DCDC_20V")
		)
		(sheetname "/DCDC/")
		(sheetfile "dcdc.kicad_sch")
		(attr smd)
		(fp_rect
			(start -0.925 -0.47)
			(end 0.925 0.47)
			(stroke
				(width 0.05)
				(type default)
			)
			(fill no)
			(layer "F.CrtYd")
		)
		(fp_rect
			(start -0.5 -0.25)
			(end 0.5 0.25)
			(stroke
				(width 0.15)
				(type solid)
			)
			(fill no)
			(layer "F.Fab")
		)
		(fp_text user "Author: Antmicro"
			(at -0.95 4.169 90)
			(layer "F.Fab")
			(effects
				(font
					(size 0.7 0.7)
					(thickness 0.15)
				)
				(justify right top)
			)
		)
		(fp_text user "${REFERENCE}"
			(at -0.95 3.168 90)
			(layer "F.Fab")
			(effects
				(font
					(size 0.7 0.7)
					(thickness 0.15)
				)
				(justify right top)
			)
		)
		(fp_text user "License: Apache-2.0"
			(at -0.95 5.169 90)
			(layer "F.Fab")
			(effects
				(font
					(size 0.7 0.7)
					(thickness 0.15)
				)
				(justify right top)
			)
		)
		(pad "1" smd roundrect
			(at -0.48 0 270)
			(size 0.59 0.64)
			(layers "F.Cu" "F.Mask" "F.Paste")
			(roundrect_rratio 0.25)
			(net 1 "GND")
			(pintype "passive")
		)
		(pad "2" smd roundrect
			(at 0.48 0 270)
			(size 0.59 0.64)
			(layers "F.Cu" "F.Mask" "F.Paste")
			(roundrect_rratio 0.25)
			(net 1210 "/DCDC/20V_MODE2")
			(pintype "passive")
		)
	)
	(footprint "antmicro-footprints:C_0805_2012Metric"
		(layer "F.Cu")
		(at 169.55 99.81 90)
		(descr "Capacitor SMD 0805")
		(tags "capacitor SMD 0805")
		(property "Reference" "C282"
			(at -4.595 0.345 90)
			(layer "F.SilkS")
			(effects
				(font
					(size 0.7 0.7)
					(thickness 0.15)
				)
				(justify left bottom)
			)
		)
		(property "Value" "C_22u_25V_0805"
			(at -2.055717 1.963152 90)
			(layer "F.Fab")
			(effects
				(font
					(size 0.7 0.7)
					(thickness 0.15)
				)
				(justify left bottom)
			)
		)
		(property "Datasheet" "https://product.samsungsem.com/mlcc/CL21A226MAYNNN.do"
			(at 0 0 90)
			(layer "F.Fab")
			(hide yes)
			(effects
				(font
					(size 1.27 1.27)
					(thickness 0.15)
				)
			)
		)
		(property "Description" "SMT Multilayer Ceramic Capacitor, 22uF, +/-20%, 25V, X5R, 0805 [2012 Metric]"
			(at 0 0 90)
			(layer "F.Fab")
			(hide yes)
			(effects
				(font
					(size 1.27 1.27)
					(thickness 0.15)
				)
			)
		)
		(property "MPN" "CL21A226MAYNNNE"
			(at 0 0 90)
			(unlocked yes)
			(layer "F.Fab")
			(hide yes)
			(effects
				(font
					(size 1 1)
					(thickness 0.15)
				)
			)
		)
		(property "Manufacturer" "Samsung Electro-Mechanics"
			(at 0 0 90)
			(unlocked yes)
			(layer "F.Fab")
			(hide yes)
			(effects
				(font
					(size 1 1)
					(thickness 0.15)
				)
			)
		)
		(property "License" "Apache-2.0"
			(at 0 0 90)
			(unlocked yes)
			(layer "F.Fab")
			(hide yes)
			(effects
				(font
					(size 1 1)
					(thickness 0.15)
				)
			)
		)
		(property "Author" "Antmicro"
			(at 0 0 90)
			(unlocked yes)
			(layer "F.Fab")
			(hide yes)
			(effects
				(font
					(size 1 1)
					(thickness 0.15)
				)
			)
		)
		(property "Val" "22u"
			(at 0 0 90)
			(unlocked yes)
			(layer "F.Fab")
			(hide yes)
			(effects
				(font
					(size 1 1)
					(thickness 0.15)
				)
			)
		)
		(property "Voltage" "25V"
			(at 0 0 90)
			(unlocked yes)
			(layer "F.Fab")
			(hide yes)
			(effects
				(font
					(size 1 1)
					(thickness 0.15)
				)
			)
		)
		(property "Dielectric" "X5R"
			(at 0 0 90)
			(unlocked yes)
			(layer "F.Fab")
			(hide yes)
			(effects
				(font
					(size 1 1)
					(thickness 0.15)
				)
			)
		)
		(property "Public" "False"
			(at 0 0 90)
			(unlocked yes)
			(layer "F.Fab")
			(hide yes)
			(effects
				(font
					(size 1 1)
					(thickness 0.15)
				)
			)
		)
		(component_classes
			(class "DCDC_SOM")
		)
		(sheetname "/DCDC/")
		(sheetfile "dcdc.kicad_sch")
		(attr smd)
		(fp_line
			(start -0.3 -0.7)
			(end 0.3 -0.7)
			(stroke
				(width 0.15)
				(type solid)
			)
			(layer "F.SilkS")
		)
		(fp_line
			(start -0.3 0.7)
			(end 0.3 0.7)
			(stroke
				(width 0.15)
				(type solid)
			)
			(layer "F.SilkS")
		)
		(fp_rect
			(start 1.95 -0.9)
			(end -1.95 0.9)
			(stroke
				(width 0.05)
				(type default)
			)
			(fill no)
			(layer "F.CrtYd")
		)
		(fp_rect
			(start -0.95 -0.675)
			(end 0.95 0.675)
			(stroke
				(width 0.15)
				(type solid)
			)
			(fill no)
			(layer "F.Fab")
		)
		(fp_text user "License: Apache-2.0"
			(at -1.9 4.947 90)
			(layer "F.Fab")
			(effects
				(font
					(size 0.7 0.7)
					(thickness 0.15)
				)
				(justify left bottom)
			)
		)
		(fp_text user "${REFERENCE}"
			(at -1.9 3.947 90)
			(layer "F.Fab")
			(effects
				(font
					(size 0.7 0.7)
					(thickness 0.15)
				)
				(justify left bottom)
			)
		)
		(fp_text user "Author: Antmicro"
			(at -1.9 5.947 90)
			(layer "F.Fab")
			(effects
				(font
					(size 0.7 0.7)
					(thickness 0.15)
				)
				(justify left bottom)
			)
		)
		(pad "1" smd roundrect
			(at -1.1 0 90)
			(size 1.2 1.3)
			(layers "F.Cu" "F.Mask" "F.Paste")
			(roundrect_rratio 0.25)
			(net 1 "GND")
			(pintype "passive")
		)
		(pad "2" smd roundrect
			(at 1.1 0 90)
			(size 1.2 1.3)
			(layers "F.Cu" "F.Mask" "F.Paste")
			(roundrect_rratio 0.25)
			(net 903 "/DCDC/16V_OUT")
			(pintype "passive")
		)
	)
	(footprint "antmicro-footprints:R_0402_1005Metric"
		(layer "F.Cu")
		(at 210.114132 93.627 180)
		(descr "Resistor SMD 0402")
		(tags "resistor SMD 0402")
		(property "Reference" "R122"
			(at 0.854132 -0.513 0)
			(layer "F.SilkS")
			(effects
				(font
					(size 0.7 0.7)
					(thickness 0.15)
				)
				(justify right top)
			)
		)
		(property "Value" "R_0R_0402"
			(at -1.011843 1.772047 0)
			(layer "F.Fab")
			(effects
				(font
					(size 0.7 0.7)
					(thickness 0.15)
				)
				(justify right top)
			)
		)
		(property "Datasheet" "https://industrial.panasonic.com/cdbs/www-data/pdf/RDA0000/AOA0000C301.pdf"
			(at 0 0 0)
			(layer "F.Fab")
			(hide yes)
			(effects
				(font
					(size 1.27 1.27)
					(thickness 0.15)
				)
			)
		)
		(property "Description" "SMD Chip Resistor, Jumper, 0 ohm, 100 mW, 0402 [1005 Metric], Thick Film, General Purpose"
			(at 0 0 0)
			(layer "F.Fab")
			(hide yes)
			(effects
				(font
					(size 1.27 1.27)
					(thickness 0.15)
				)
			)
		)
		(property "Manufacturer" "Panasonic"
			(at 0 0 180)
			(unlocked yes)
			(layer "F.Fab")
			(hide yes)
			(effects
				(font
					(size 1 1)
					(thickness 0.15)
				)
			)
		)
		(property "MPN" "ERJ2GE0R00X"
			(at 0 0 180)
			(unlocked yes)
			(layer "F.Fab")
			(hide yes)
			(effects
				(font
					(size 1 1)
					(thickness 0.15)
				)
			)
		)
		(property "Val" "0R"
			(at 0 0 180)
			(unlocked yes)
			(layer "F.Fab")
			(hide yes)
			(effects
				(font
					(size 1 1)
					(thickness 0.15)
				)
			)
		)
		(property "License" "Apache-2.0"
			(at 0 0 180)
			(unlocked yes)
			(layer "F.Fab")
			(hide yes)
			(effects
				(font
					(size 1 1)
					(thickness 0.15)
				)
			)
		)
		(property "Author" "Antmicro"
			(at 0 0 180)
			(unlocked yes)
			(layer "F.Fab")
			(hide yes)
			(effects
				(font
					(size 1 1)
					(thickness 0.15)
				)
			)
		)
		(property "Tolerance" "~"
			(at 0 0 180)
			(unlocked yes)
			(layer "F.Fab")
			(hide yes)
			(effects
				(font
					(size 1 1)
					(thickness 0.15)
				)
			)
		)
		(property "Current" "1A"
			(at 0 0 180)
			(unlocked yes)
			(layer "F.Fab")
			(hide yes)
			(effects
				(font
					(size 1 1)
					(thickness 0.15)
				)
			)
		)
		(sheetname "/USB DP Alt mode/")
		(sheetfile "usb_dp.kicad_sch")
		(attr smd exclude_from_pos_files exclude_from_bom dnp)
		(fp_rect
			(start -0.925 -0.47)
			(end 0.925 0.47)
			(stroke
				(width 0.05)
				(type default)
			)
			(fill no)
			(layer "F.CrtYd")
		)
		(fp_rect
			(start -0.5 -0.25)
			(end 0.5 0.25)
			(stroke
				(width 0.15)
				(type solid)
			)
			(fill no)
			(layer "F.Fab")
		)
		(fp_text user "Author: Antmicro"
			(at -0.95 4.169 0)
			(layer "F.Fab")
			(effects
				(font
					(size 0.7 0.7)
					(thickness 0.15)
				)
				(justify right top)
			)
		)
		(fp_text user "${REFERENCE}"
			(at -0.95 3.168 0)
			(layer "F.Fab")
			(effects
				(font
					(size 0.7 0.7)
					(thickness 0.15)
				)
				(justify right top)
			)
		)
		(fp_text user "License: Apache-2.0"
			(at -0.95 5.169 0)
			(layer "F.Fab")
			(effects
				(font
					(size 0.7 0.7)
					(thickness 0.15)
				)
				(justify right top)
			)
		)
		(pad "1" smd roundrect
			(at -0.48 0 180)
			(size 0.59 0.64)
			(layers "F.Cu" "F.Mask" "F.Paste")
			(roundrect_rratio 0.25)
			(net 942 "/USB DP Alt mode/USBC1_FLIP")
			(pintype "passive")
		)
		(pad "2" smd roundrect
			(at 0.48 0 180)
			(size 0.59 0.64)
			(layers "F.Cu" "F.Mask" "F.Paste")
			(roundrect_rratio 0.25)
			(net 853 "/I2C_{SYS}.SCL")
			(pintype "passive")
		)
	)
	(footprint "antmicro-footprints:R_0402_1005Metric"
		(layer "F.Cu")
		(at 214 133.8 180)
		(descr "Resistor SMD 0402")
		(tags "resistor SMD 0402")
		(property "Reference" "R67"
			(at -3.07 0.33 0)
			(layer "F.SilkS")
			(effects
				(font
					(size 0.7 0.7)
					(thickness 0.15)
				)
				(justify right top)
			)
		)
		(property "Value" "R_10k_0402"
			(at -1.011843 1.772047 0)
			(layer "F.Fab")
			(effects
				(font
					(size 0.7 0.7)
					(thickness 0.15)
				)
				(justify right top)
			)
		)
		(property "Datasheet" "https://www.bourns.com/docs/product-datasheets/cr.pdf"
			(at 0 0 0)
			(layer "F.Fab")
			(hide yes)
			(effects
				(font
					(size 1.27 1.27)
					(thickness 0.15)
				)
			)
		)
		(property "Description" "SMD Chip Resistor, 10 kohm, ± 1%, 62.5 mW, 0402 [1005 Metric], Thick Film, General Purpose"
			(at 0 0 0)
			(layer "F.Fab")
			(hide yes)
			(effects
				(font
					(size 1.27 1.27)
					(thickness 0.15)
				)
			)
		)
		(property "Manufacturer" "Bourns"
			(at 0 0 180)
			(unlocked yes)
			(layer "F.Fab")
			(hide yes)
			(effects
				(font
					(size 1 1)
					(thickness 0.15)
				)
			)
		)
		(property "MPN" "CR0402-FX-1002GLF"
			(at 0 0 180)
			(unlocked yes)
			(layer "F.Fab")
			(hide yes)
			(effects
				(font
					(size 1 1)
					(thickness 0.15)
				)
			)
		)
		(property "Val" "10k"
			(at 0 0 180)
			(unlocked yes)
			(layer "F.Fab")
			(hide yes)
			(effects
				(font
					(size 1 1)
					(thickness 0.15)
				)
			)
		)
		(property "License" "Apache-2.0"
			(at 0 0 180)
			(unlocked yes)
			(layer "F.Fab")
			(hide yes)
			(effects
				(font
					(size 1 1)
					(thickness 0.15)
				)
			)
		)
		(property "Author" "Antmicro"
			(at 0 0 180)
			(unlocked yes)
			(layer "F.Fab")
			(hide yes)
			(effects
				(font
					(size 1 1)
					(thickness 0.15)
				)
			)
		)
		(property "Tolerance" "1%"
			(at 0 0 180)
			(unlocked yes)
			(layer "F.Fab")
			(hide yes)
			(effects
				(font
					(size 1 1)
					(thickness 0.15)
				)
			)
		)
		(sheetname "/USB Hub/")
		(sheetfile "usb_hub.kicad_sch")
		(attr smd)
		(fp_rect
			(start -0.925 -0.47)
			(end 0.925 0.47)
			(stroke
				(width 0.05)
				(type default)
			)
			(fill no)
			(layer "F.CrtYd")
		)
		(fp_rect
			(start -0.5 -0.25)
			(end 0.5 0.25)
			(stroke
				(width 0.15)
				(type solid)
			)
			(fill no)
			(layer "F.Fab")
		)
		(fp_text user "${REFERENCE}"
			(at -0.95 3.168 0)
			(layer "F.Fab")
			(effects
				(font
					(size 0.7 0.7)
					(thickness 0.15)
				)
				(justify right top)
			)
		)
		(fp_text user "Author: Antmicro"
			(at -0.95 4.169 0)
			(layer "F.Fab")
			(effects
				(font
					(size 0.7 0.7)
					(thickness 0.15)
				)
				(justify right top)
			)
		)
		(fp_text user "License: Apache-2.0"
			(at -0.95 5.169 0)
			(layer "F.Fab")
			(effects
				(font
					(size 0.7 0.7)
					(thickness 0.15)
				)
				(justify right top)
			)
		)
		(pad "1" smd roundrect
			(at -0.48 0 180)
			(size 0.59 0.64)
			(layers "F.Cu" "F.Mask" "F.Paste")
			(roundrect_rratio 0.25)
			(net 2 "+3V3")
			(pintype "passive")
		)
		(pad "2" smd roundrect
			(at 0.48 0 180)
			(size 0.59 0.64)
			(layers "F.Cu" "F.Mask" "F.Paste")
			(roundrect_rratio 0.25)
			(net 527 "/USB Hub/~{RESET}")
			(pintype "passive")
		)
	)
	(footprint "antmicro-footprints:R_0402_1005Metric"
		(layer "F.Cu")
		(at 188.3 122.6 90)
		(descr "Resistor SMD 0402")
		(tags "resistor SMD 0402")
		(property "Reference" "R380"
			(at 7.1 -2.4 90)
			(layer "F.SilkS")
			(effects
				(font
					(size 0.7 0.7)
					(thickness 0.15)
				)
				(justify left bottom)
			)
		)
		(property "Value" "R_0R_0402"
			(at -1.011843 1.772047 90)
			(layer "F.Fab")
			(effects
				(font
					(size 0.7 0.7)
					(thickness 0.15)
				)
				(justify left bottom)
			)
		)
		(property "Datasheet" "https://industrial.panasonic.com/cdbs/www-data/pdf/RDA0000/AOA0000C301.pdf"
			(at 0 0 90)
			(layer "F.Fab")
			(hide yes)
			(effects
				(font
					(size 1.27 1.27)
					(thickness 0.15)
				)
			)
		)
		(property "Description" "SMD Chip Resistor, Jumper, 0 ohm, 100 mW, 0402 [1005 Metric], Thick Film, General Purpose"
			(at 0 0 90)
			(layer "F.Fab")
			(hide yes)
			(effects
				(font
					(size 1.27 1.27)
					(thickness 0.15)
				)
			)
		)
		(property "MPN" "ERJ2GE0R00X"
			(at 0 0 90)
			(unlocked yes)
			(layer "F.Fab")
			(hide yes)
			(effects
				(font
					(size 1 1)
					(thickness 0.15)
				)
			)
		)
		(property "Manufacturer" "Panasonic"
			(at 0 0 90)
			(unlocked yes)
			(layer "F.Fab")
			(hide yes)
			(effects
				(font
					(size 1 1)
					(thickness 0.15)
				)
			)
		)
		(property "License" "Apache-2.0"
			(at 0 0 90)
			(unlocked yes)
			(layer "F.Fab")
			(hide yes)
			(effects
				(font
					(size 1 1)
					(thickness 0.15)
				)
			)
		)
		(property "Author" "Antmicro"
			(at 0 0 90)
			(unlocked yes)
			(layer "F.Fab")
			(hide yes)
			(effects
				(font
					(size 1 1)
					(thickness 0.15)
				)
			)
		)
		(property "Val" "0R"
			(at 0 0 90)
			(unlocked yes)
			(layer "F.Fab")
			(hide yes)
			(effects
				(font
					(size 1 1)
					(thickness 0.15)
				)
			)
		)
		(property "Tolerance" "~"
			(at 0 0 90)
			(unlocked yes)
			(layer "F.Fab")
			(hide yes)
			(effects
				(font
					(size 1 1)
					(thickness 0.15)
				)
			)
		)
		(property "Current" "1A"
			(at 0 0 90)
			(unlocked yes)
			(layer "F.Fab")
			(hide yes)
			(effects
				(font
					(size 1 1)
					(thickness 0.15)
				)
			)
		)
		(sheetname "/USB Hub/")
		(sheetfile "usb_hub.kicad_sch")
		(attr smd exclude_from_pos_files exclude_from_bom dnp)
		(fp_rect
			(start -0.925 -0.47)
			(end 0.925 0.47)
			(stroke
				(width 0.05)
				(type default)
			)
			(fill no)
			(layer "F.CrtYd")
		)
		(fp_rect
			(start -0.5 -0.25)
			(end 0.5 0.25)
			(stroke
				(width 0.15)
				(type solid)
			)
			(fill no)
			(layer "F.Fab")
		)
		(fp_text user "License: Apache-2.0"
			(at -0.95 5.169 90)
			(layer "F.Fab")
			(effects
				(font
					(size 0.7 0.7)
					(thickness 0.15)
				)
				(justify left bottom)
			)
		)
		(fp_text user "${REFERENCE}"
			(at -0.95 3.168 90)
			(layer "F.Fab")
			(effects
				(font
					(size 0.7 0.7)
					(thickness 0.15)
				)
				(justify left bottom)
			)
		)
		(fp_text user "Author: Antmicro"
			(at -0.95 4.169 90)
			(layer "F.Fab")
			(effects
				(font
					(size 0.7 0.7)
					(thickness 0.15)
				)
				(justify left bottom)
			)
		)
		(pad "1" smd roundrect
			(at -0.48 0 90)
			(size 0.59 0.64)
			(layers "F.Cu" "F.Mask" "F.Paste")
			(roundrect_rratio 0.25)
			(net 924 "/USB Hub/HUB_SPI_D3")
			(pintype "passive")
		)
		(pad "2" smd roundrect
			(at 0.48 0 90)
			(size 0.59 0.64)
			(layers "F.Cu" "F.Mask" "F.Paste")
			(roundrect_rratio 0.25)
			(net 1165 "/USB Hub/HUB_~{HOLD}")
			(pintype "passive")
		)
	)
)
